(kicad_pcb
	(version 20260206)
	(generator "pcbnew")
	(generator_version "10.0")
	(general
		(thickness 1.6)
		(legacy_teardrops no)
	)
	(paper "A4")
	(title_block
		(title "Bryce Canyon_SCC_16316-1_OCP.brd")
		(comment 1 "Bryce Canyon / footprints 1324-1330 of 1561")
	)
	(layers
		(0 "F.Cu" signal "TOP")
		(4 "In1.Cu" signal "L2GND")
		(6 "In2.Cu" signal "L3")
		(8 "In3.Cu" signal "L4VCC")
		(10 "In4.Cu" signal "L5VCC")
		(12 "In5.Cu" signal "L6")
		(14 "In6.Cu" signal "L7GND")
		(2 "B.Cu" signal "BOTTOM")
		(9 "F.Adhes" user "F.Adhesive")
		(11 "B.Adhes" user "B.Adhesive")
		(13 "F.Paste" user "Package Geometry/Pastemask Top")
		(15 "B.Paste" user "Package Geometry/Pastemask Bottom")
		(5 "F.SilkS" user "Ref Des/Silkscreen Top")
		(7 "B.SilkS" user "Ref Des/Silkscreen Bottom")
		(1 "F.Mask" user "Board Geometry/Soldermask Top")
		(3 "B.Mask" user "Board Geometry/Soldermask Bottom")
		(17 "Dwgs.User" user "User.Drawings")
		(19 "Cmts.User" user "User.Comments")
		(21 "Eco1.User" user "User.Eco1")
		(23 "Eco2.User" user "User.Eco2")
		(25 "Edge.Cuts" user "Board Geometry/Outline")
		(27 "Margin" user)
		(31 "F.CrtYd" user "Package Geometry/Place Bound Top")
		(29 "B.CrtYd" user "Package Geometry/Place Bound Bottom")
		(35 "F.Fab" user "Ref Des/Assembly Top")
		(33 "B.Fab" user "Ref Des/Assembly Bottom")
	)
	(footprint ""
		(layer "B.Cu")
		(at 169.905172 -36.02355 90)
		(property "Reference" "C403"
			(at 0 0 90)
			(layer "B.SilkS")
			(hide yes)
			(effects
				(font
					(size 1.27 1.27)
				)
				(justify mirror)
			)
		)
		(property "Value" "SCD1U16V2KX-3GP"
			(at -1.1811 -2.7051 90)
			(unlocked yes)
			(layer "B.Fab")
			(hide yes)
			(effects
				(font
					(size 1.016 1.016)
					(thickness 0.1524)
				)
				(justify mirror)
			)
		)
		(property "Device Type" "C402H22"
			(at -1.1811 -4.2291 90)
			(unlocked yes)
			(layer "B.Fab")
			(hide yes)
			(effects
				(font
					(size 1.016 1.016)
					(thickness 0.1524)
				)
				(justify mirror)
			)
		)
		(duplicate_pad_numbers_are_jumpers no)
		(fp_rect
			(start 0.4318 0.9525)
			(end -0.4318 -0.9525)
			(stroke
				(width 0)
				(type default)
			)
			(fill no)
			(layer "B.CrtYd")
		)
		(fp_rect
			(start 0.4318 0.9525)
			(end -0.4318 -0.9525)
			(stroke
				(width 0)
				(type default)
			)
			(fill no)
			(layer "B.Fab")
		)
		(pad "1" smd custom
			(at 0 -0.4445 270)
			(size 0.1524 0.1524)
			(layers "B.Cu" "B.Mask" "B.Paste")
			(net "SAS0_AVDD")
			(options
				(clearance outline)
				(anchor circle)
			)
			(primitives
				(gr_poly
					(pts
						(arc
							(start 0.3048 0.2032)
							(mid 0.275042 0.275042)
							(end 0.2032 0.3048)
						)
						(arc
							(start -0.2032 0.3048)
							(mid -0.275042 0.275042)
							(end -0.3048 0.2032)
						)
						(arc
							(start -0.3048 -0.2032)
							(mid -0.275042 -0.275042)
							(end -0.2032 -0.3048)
						)
						(arc
							(start 0.2032 -0.3048)
							(mid 0.275042 -0.275042)
							(end 0.3048 -0.2032)
						)
					)
					(width 0)
					(fill yes)
				)
			)
		)
		(pad "2" smd custom
			(at 0 0.4445 270)
			(size 0.1524 0.1524)
			(layers "B.Cu" "B.Mask" "B.Paste")
			(net "GND")
			(options
				(clearance outline)
				(anchor circle)
			)
			(primitives
				(gr_poly
					(pts
						(arc
							(start 0.3048 0.2032)
							(mid 0.275042 0.275042)
							(end 0.2032 0.3048)
						)
						(arc
							(start -0.2032 0.3048)
							(mid -0.275042 0.275042)
							(end -0.3048 0.2032)
						)
						(arc
							(start -0.3048 -0.2032)
							(mid -0.275042 -0.275042)
							(end -0.2032 -0.3048)
						)
						(arc
							(start 0.2032 -0.3048)
							(mid 0.275042 -0.275042)
							(end 0.3048 -0.2032)
						)
					)
					(width 0)
					(fill yes)
				)
			)
		)
	)
	(footprint ""
		(layer "B.Cu")
		(at 193.3956 -24.31542 -90)
		(property "Reference" "Q3"
			(at 0 0 90)
			(layer "B.SilkS")
			(hide yes)
			(effects
				(font
					(size 1.27 1.27)
				)
				(justify mirror)
			)
		)
		(property "Value" "SSM3K324R-GP"
			(at -0.127 -8.9662 270)
			(unlocked yes)
			(layer "B.Fab")
			(hide yes)
			(effects
				(font
					(size 1.016 1.016)
					(thickness 0.1524)
				)
				(justify mirror)
			)
		)
		(property "Device Type" "SOT23DGS2D4H35"
			(at -0.127 -10.4902 270)
			(unlocked yes)
			(layer "B.Fab")
			(hide yes)
			(effects
				(font
					(size 1.016 1.016)
					(thickness 0.1524)
				)
				(justify mirror)
			)
		)
		(duplicate_pad_numbers_are_jumpers no)
		(fp_line
			(start -1.651 1.778)
			(end -1.651 -1.778)
			(stroke
				(width 0.1524)
				(type default)
			)
			(layer "B.SilkS")
		)
		(fp_line
			(start 1.651 1.778)
			(end -1.651 1.778)
			(stroke
				(width 0.1524)
				(type default)
			)
			(layer "B.SilkS")
		)
		(fp_line
			(start -1.651 -1.778)
			(end 1.651 -1.778)
			(stroke
				(width 0.1524)
				(type default)
			)
			(layer "B.SilkS")
		)
		(fp_line
			(start 1.651 -1.778)
			(end 1.651 1.778)
			(stroke
				(width 0.1524)
				(type default)
			)
			(layer "B.SilkS")
		)
		(fp_poly
			(pts
				(xy 1.778 1.8796) (xy 1.778 -1.8796) (xy -1.778 -1.8796) (xy -1.778 1.8796)
			)
			(stroke
				(width 0)
				(type default)
			)
			(fill no)
			(layer "B.CrtYd")
		)
		(fp_poly
			(pts
				(xy 1.778 1.8796) (xy 1.778 -1.8796) (xy -1.778 -1.8796) (xy -1.778 1.8796)
			)
			(stroke
				(width 0)
				(type default)
			)
			(fill no)
			(layer "B.Fab")
		)
		(pad "D" smd custom
			(at 0 -0.9525 90)
			(size 0.1905 0.1905)
			(layers "B.Cu" "B.Mask" "B.Paste")
			(net "SYS_HB_LED_D")
			(options
				(clearance outline)
				(anchor circle)
			)
			(primitives
				(gr_poly
					(pts
						(arc
							(start -0.1778 -0.5715)
							(mid -0.321484 -0.511984)
							(end -0.381 -0.3683)
						)
						(arc
							(start -0.381 0.3683)
							(mid -0.321484 0.511984)
							(end -0.1778 0.5715)
						)
						(arc
							(start 0.1778 0.5715)
							(mid 0.321484 0.511984)
							(end 0.381 0.3683)
						)
						(arc
							(start 0.381 -0.3683)
							(mid 0.321484 -0.511984)
							(end 0.1778 -0.5715)
						)
					)
					(width 0)
					(fill yes)
				)
			)
		)
		(pad "G" smd custom
			(at 0.98425 0.9525 90)
			(size 0.1905 0.1905)
			(layers "B.Cu" "B.Mask" "B.Paste")
			(net "SYS_HB_LED")
			(options
				(clearance outline)
				(anchor circle)
			)
			(primitives
				(gr_poly
					(pts
						(arc
							(start -0.1778 -0.5715)
							(mid -0.321484 -0.511984)
							(end -0.381 -0.3683)
						)
						(arc
							(start -0.381 0.3683)
							(mid -0.321484 0.511984)
							(end -0.1778 0.5715)
						)
						(arc
							(start 0.1778 0.5715)
							(mid 0.321484 0.511984)
							(end 0.381 0.3683)
						)
						(arc
							(start 0.381 -0.3683)
							(mid 0.321484 -0.511984)
							(end 0.1778 -0.5715)
						)
					)
					(width 0)
					(fill yes)
				)
			)
		)
		(pad "S" smd custom
			(at -0.98425 0.9525 90)
			(size 0.1905 0.1905)
			(layers "B.Cu" "B.Mask" "B.Paste")
			(net "GND")
			(options
				(clearance outline)
				(anchor circle)
			)
			(primitives
				(gr_poly
					(pts
						(arc
							(start -0.1778 -0.5715)
							(mid -0.321484 -0.511984)
							(end -0.381 -0.3683)
						)
						(arc
							(start -0.381 0.3683)
							(mid -0.321484 0.511984)
							(end -0.1778 0.5715)
						)
						(arc
							(start 0.1778 0.5715)
							(mid 0.321484 0.511984)
							(end 0.381 0.3683)
						)
						(arc
							(start 0.381 -0.3683)
							(mid 0.321484 -0.511984)
							(end 0.1778 -0.5715)
						)
					)
					(width 0)
					(fill yes)
				)
			)
		)
	)
	(footprint ""
		(layer "B.Cu")
		(at 181.995318 -47.630842)
		(property "Reference" "C500"
			(at 0 0 0)
			(layer "B.SilkS")
			(hide yes)
			(effects
				(font
					(size 1.27 1.27)
				)
				(justify mirror)
			)
		)
		(property "Value" "SC1KP50V2KX-1GP"
			(at -1.1811 -2.7051 0)
			(unlocked yes)
			(layer "B.Fab")
			(hide yes)
			(effects
				(font
					(size 1.016 1.016)
					(thickness 0.1524)
				)
				(justify mirror)
			)
		)
		(property "Device Type" "C402H22"
			(at -1.1811 -4.2291 0)
			(unlocked yes)
			(layer "B.Fab")
			(hide yes)
			(effects
				(font
					(size 1.016 1.016)
					(thickness 0.1524)
				)
				(justify mirror)
			)
		)
		(duplicate_pad_numbers_are_jumpers no)
		(fp_rect
			(start 0.4318 0.9525)
			(end -0.4318 -0.9525)
			(stroke
				(width 0)
				(type default)
			)
			(fill no)
			(layer "B.CrtYd")
		)
		(fp_rect
			(start 0.4318 0.9525)
			(end -0.4318 -0.9525)
			(stroke
				(width 0)
				(type default)
			)
			(fill no)
			(layer "B.Fab")
		)
		(pad "1" smd custom
			(at 0 -0.4445 180)
			(size 0.1524 0.1524)
			(layers "B.Cu" "B.Mask" "B.Paste")
			(net "P1V8_C")
			(options
				(clearance outline)
				(anchor circle)
			)
			(primitives
				(gr_poly
					(pts
						(arc
							(start 0.3048 0.2032)
							(mid 0.275042 0.275042)
							(end 0.2032 0.3048)
						)
						(arc
							(start -0.2032 0.3048)
							(mid -0.275042 0.275042)
							(end -0.3048 0.2032)
						)
						(arc
							(start -0.3048 -0.2032)
							(mid -0.275042 -0.275042)
							(end -0.2032 -0.3048)
						)
						(arc
							(start 0.2032 -0.3048)
							(mid 0.275042 -0.275042)
							(end 0.3048 -0.2032)
						)
					)
					(width 0)
					(fill yes)
				)
			)
		)
		(pad "2" smd custom
			(at 0 0.4445 180)
			(size 0.1524 0.1524)
			(layers "B.Cu" "B.Mask" "B.Paste")
			(net "GND")
			(options
				(clearance outline)
				(anchor circle)
			)
			(primitives
				(gr_poly
					(pts
						(arc
							(start 0.3048 0.2032)
							(mid 0.275042 0.275042)
							(end 0.2032 0.3048)
						)
						(arc
							(start -0.2032 0.3048)
							(mid -0.275042 0.275042)
							(end -0.3048 0.2032)
						)
						(arc
							(start -0.3048 -0.2032)
							(mid -0.275042 -0.275042)
							(end -0.2032 -0.3048)
						)
						(arc
							(start 0.2032 -0.3048)
							(mid 0.275042 -0.275042)
							(end 0.3048 -0.2032)
						)
					)
					(width 0)
					(fill yes)
				)
			)
		)
	)
	(footprint ""
		(layer "B.Cu")
		(at 129.397252 -59.371992 90)
		(property "Reference" "C264"
			(at 0 0 90)
			(layer "B.SilkS")
			(hide yes)
			(effects
				(font
					(size 1.27 1.27)
				)
				(justify mirror)
			)
		)
		(property "Value" "SC1U6D3V1MX-GP"
			(at -1.9177 2.0193 90)
			(unlocked yes)
			(layer "B.Fab")
			(hide yes)
			(effects
				(font
					(size 1.016 1.016)
					(thickness 0.1524)
				)
				(justify mirror)
			)
		)
		(property "Device Type" "C0201H14"
			(at -1.9177 0.4953 90)
			(unlocked yes)
			(layer "B.Fab")
			(hide yes)
			(effects
				(font
					(size 1.016 1.016)
					(thickness 0.1524)
				)
				(justify mirror)
			)
		)
		(duplicate_pad_numbers_are_jumpers no)
		(fp_rect
			(start 0.1524 0.3048)
			(end -0.1524 -0.3048)
			(stroke
				(width 0)
				(type default)
			)
			(fill no)
			(layer "B.CrtYd")
		)
		(fp_poly
			(pts
				(xy 0.2794 0.6477) (xy 0.2794 -0.6477) (xy -0.2794 -0.6477) (xy -0.2794 -0.1905) (xy -0.1524 -0.1905)
				(xy -0.1524 -0.3048) (xy 0.1524 -0.3048) (xy 0.1524 0.3048) (xy -0.1524 0.3048) (xy -0.1524 -0.1778)
				(xy -0.2794 -0.1778) (xy -0.2794 0.6477)
			)
			(stroke
				(width 0)
				(type default)
			)
			(fill no)
			(layer "B.CrtYd")
		)
		(fp_rect
			(start 0.2794 0.6477)
			(end -0.2794 -0.6477)
			(stroke
				(width 0)
				(type default)
			)
			(fill no)
			(layer "B.Fab")
		)
		(pad "1" smd custom
			(at 0 -0.2794 270)
			(size 0.0762 0.0762)
			(layers "B.Cu" "B.Mask" "B.Paste")
			(net "GB_VDDA")
			(options
				(clearance outline)
				(anchor circle)
			)
			(primitives
				(gr_poly
					(pts
						(arc
							(start 0.1524 0.127)
							(mid 0.137521 0.162921)
							(end 0.1016 0.1778)
						)
						(arc
							(start -0.1016 0.1778)
							(mid -0.137521 0.162921)
							(end -0.1524 0.127)
						)
						(arc
							(start -0.1524 -0.127)
							(mid -0.137521 -0.162921)
							(end -0.1016 -0.1778)
						)
						(arc
							(start 0.1016 -0.1778)
							(mid 0.137521 -0.162921)
							(end 0.1524 -0.127)
						)
					)
					(width 0)
					(fill yes)
				)
			)
		)
		(pad "2" smd custom
			(at 0 0.2794 270)
			(size 0.0762 0.0762)
			(layers "B.Cu" "B.Mask" "B.Paste")
			(net "GND")
			(options
				(clearance outline)
				(anchor circle)
			)
			(primitives
				(gr_poly
					(pts
						(arc
							(start 0.1524 0.127)
							(mid 0.137521 0.162921)
							(end 0.1016 0.1778)
						)
						(arc
							(start -0.1016 0.1778)
							(mid -0.137521 0.162921)
							(end -0.1524 0.127)
						)
						(arc
							(start -0.1524 -0.127)
							(mid -0.137521 -0.162921)
							(end -0.1016 -0.1778)
						)
						(arc
							(start 0.1016 -0.1778)
							(mid 0.137521 -0.162921)
							(end 0.1524 -0.127)
						)
					)
					(width 0)
					(fill yes)
				)
			)
		)
	)
	(footprint ""
		(layer "B.Cu")
		(at 165.537388 -50.441352)
		(property "Reference" "TP118"
			(at 0 0 0)
			(layer "B.SilkS")
			(hide yes)
			(effects
				(font
					(size 1.27 1.27)
				)
				(justify mirror)
			)
		)
		(property "Value" "TPAD28-2-GP"
			(at 0.0127 -1.6637 0)
			(unlocked yes)
			(layer "B.Fab")
			(hide yes)
			(effects
				(font
					(size 1.016 1.016)
					(thickness 0.1524)
				)
				(justify mirror)
			)
		)
		(property "Device Type" "TPAD28"
			(at 0.0127 -3.1877 0)
			(unlocked yes)
			(layer "B.Fab")
			(hide yes)
			(effects
				(font
					(size 1.016 1.016)
					(thickness 0.1524)
				)
				(justify mirror)
			)
		)
		(duplicate_pad_numbers_are_jumpers no)
		(fp_poly
			(pts
				(arc
					(start 0.3556 0)
					(mid -0.3556 0)
					(end 0.3556 0)
				)
			)
			(stroke
				(width 0)
				(type default)
			)
			(fill no)
			(layer "B.CrtYd")
		)
		(fp_poly
			(pts
				(arc
					(start 0.6096 0)
					(mid -0.6096 0)
					(end 0.6096 0)
				)
			)
			(stroke
				(width 0)
				(type default)
			)
			(fill no)
			(layer "B.Fab")
		)
		(pad "1" smd circle
			(at 0 0 180)
			(size 0.7112 0.7112)
			(layers "B.Cu" "B.Mask" "B.Paste")
			(net "ICE_SEL")
		)
	)
	(footprint ""
		(layer "B.Cu")
		(at 123.522232 -80.554068 180)
		(property "Reference" "C147"
			(at 0 0 0)
			(layer "B.SilkS")
			(hide yes)
			(effects
				(font
					(size 1.27 1.27)
				)
				(justify mirror)
			)
		)
		(property "Value" "SCD1U6D3V1KX-GP"
			(at 2.8321 -1.7399 180)
			(unlocked yes)
			(layer "B.Fab")
			(hide yes)
			(effects
				(font
					(size 1.016 1.016)
					(thickness 0.1524)
				)
				(justify mirror)
			)
		)
		(property "Device Type" "C0201H13"
			(at 2.8321 -3.2639 180)
			(unlocked yes)
			(layer "B.Fab")
			(hide yes)
			(effects
				(font
					(size 1.016 1.016)
					(thickness 0.1524)
				)
				(justify mirror)
			)
		)
		(duplicate_pad_numbers_are_jumpers no)
		(fp_rect
			(start 0.2794 0.6477)
			(end -0.2794 -0.6477)
			(stroke
				(width 0)
				(type default)
			)
			(fill no)
			(layer "B.CrtYd")
		)
		(fp_rect
			(start 0.2794 0.6477)
			(end -0.2794 -0.6477)
			(stroke
				(width 0)
				(type default)
			)
			(fill no)
			(layer "B.Fab")
		)
		(pad "1" smd custom
			(at 0 -0.2794)
			(size 0.0762 0.0762)
			(layers "B.Cu" "B.Mask" "B.Paste")
			(net "P1V8_E")
			(options
				(clearance outline)
				(anchor circle)
			)
			(primitives
				(gr_poly
					(pts
						(arc
							(start 0.1524 0.127)
							(mid 0.137521 0.162921)
							(end 0.1016 0.1778)
						)
						(arc
							(start -0.1016 0.1778)
							(mid -0.137521 0.162921)
							(end -0.1524 0.127)
						)
						(arc
							(start -0.1524 -0.127)
							(mid -0.137521 -0.162921)
							(end -0.1016 -0.1778)
						)
						(arc
							(start 0.1016 -0.1778)
							(mid 0.137521 -0.162921)
							(end 0.1524 -0.127)
						)
					)
					(width 0)
					(fill yes)
				)
			)
		)
		(pad "2" smd custom
			(at 0 0.2794)
			(size 0.0762 0.0762)
			(layers "B.Cu" "B.Mask" "B.Paste")
			(net "GND")
			(options
				(clearance outline)
				(anchor circle)
			)
			(primitives
				(gr_poly
					(pts
						(arc
							(start 0.1524 0.127)
							(mid 0.137521 0.162921)
							(end 0.1016 0.1778)
						)
						(arc
							(start -0.1016 0.1778)
							(mid -0.137521 0.162921)
							(end -0.1524 0.127)
						)
						(arc
							(start -0.1524 -0.127)
							(mid -0.137521 -0.162921)
							(end -0.1016 -0.1778)
						)
						(arc
							(start 0.1016 -0.1778)
							(mid 0.137521 -0.162921)
							(end 0.1524 -0.127)
						)
					)
					(width 0)
					(fill yes)
				)
			)
		)
	)
	(footprint ""
		(layer "B.Cu")
		(at 197.231 -28.321 180)
		(property "Reference" "C377"
			(at 0 0 0)
			(layer "B.SilkS")
			(hide yes)
			(effects
				(font
					(size 1.27 1.27)
				)
				(justify mirror)
			)
		)
		(property "Value" "SC22U6D3V3MX-9-GP-U"
			(at 0 -2.8194 180)
			(unlocked yes)
			(layer "B.Fab")
			(hide yes)
			(effects
				(font
					(size 1.016 1.016)
					(thickness 0.1524)
				)
				(justify mirror)
			)
		)
		(property "Device Type" "C603H40"
			(at 0 -4.3434 180)
			(unlocked yes)
			(layer "B.Fab")
			(hide yes)
			(effects
				(font
					(size 1.016 1.016)
					(thickness 0.1524)
				)
				(justify mirror)
			)
		)
		(duplicate_pad_numbers_are_jumpers no)
		(fp_line
			(start -0.508 0)
			(end 0.508 0)
			(stroke
				(width 0.2032)
				(type default)
			)
			(layer "B.SilkS")
		)
		(fp_rect
			(start 0.5842 1.3335)
			(end -0.5842 -1.3335)
			(stroke
				(width 0)
				(type default)
			)
			(fill no)
			(layer "B.CrtYd")
		)
		(fp_rect
			(start 0.5842 1.3335)
			(end -0.5842 -1.3335)
			(stroke
				(width 0)
				(type default)
			)
			(fill no)
			(layer "B.Fab")
		)
		(pad "1" smd custom
			(at 0 -0.762)
			(size 0.2159 0.2159)
			(layers "B.Cu" "B.Mask" "B.Paste")
			(net "PCE_VDDH")
			(options
				(clearance outline)
				(anchor circle)
			)
			(primitives
				(gr_poly
					(pts
						(arc
							(start -0.3302 0.4318)
							(mid -0.402042 0.402042)
							(end -0.4318 0.3302)
						)
						(arc
							(start -0.4318 -0.3302)
							(mid -0.402042 -0.402042)
							(end -0.3302 -0.4318)
						)
						(arc
							(start 0.3302 -0.4318)
							(mid 0.402042 -0.402042)
							(end 0.4318 -0.3302)
						)
						(arc
							(start 0.4318 0.3302)
							(mid 0.402042 0.402042)
							(end 0.3302 0.4318)
						)
					)
					(width 0)
					(fill yes)
				)
			)
		)
		(pad "2" smd custom
			(at 0 0.762)
			(size 0.2159 0.2159)
			(layers "B.Cu" "B.Mask" "B.Paste")
			(net "GND")
			(options
				(clearance outline)
				(anchor circle)
			)
			(primitives
				(gr_poly
					(pts
						(arc
							(start -0.3302 0.4318)
							(mid -0.402042 0.402042)
							(end -0.4318 0.3302)
						)
						(arc
							(start -0.4318 -0.3302)
							(mid -0.402042 -0.402042)
							(end -0.3302 -0.4318)
						)
						(arc
							(start 0.3302 -0.4318)
							(mid 0.402042 -0.402042)
							(end 0.4318 -0.3302)
						)
						(arc
							(start 0.4318 0.3302)
							(mid 0.402042 0.402042)
							(end 0.3302 0.4318)
						)
					)
					(width 0)
					(fill yes)
				)
			)
		)
	)
)
